(kicad_pcb
	(version 20241229)
	(generator "pcbnew")
	(generator_version "9.0")
	(general
		(thickness 1.6296)
		(legacy_teardrops no)
	)
	(paper "A3")
	(title_block
		(title "Thunderbolt to 10GbE adapter")
		(date "2026-04-21")
		(rev "1.1.0")
		(company "Antmicro Ltd")
		(comment 1 "www.antmicro.com")
		(comment 9 "footprints 662-666 of 703")
	)
	(layers
		(0 "F.Cu" signal)
		(4 "In1.Cu" signal)
		(6 "In2.Cu" signal)
		(8 "In3.Cu" signal)
		(10 "In4.Cu" signal)
		(12 "In5.Cu" signal)
		(14 "In6.Cu" signal)
		(2 "B.Cu" signal)
		(9 "F.Adhes" user "F.Adhesive")
		(11 "B.Adhes" user "B.Adhesive")
		(13 "F.Paste" user)
		(15 "B.Paste" user)
		(5 "F.SilkS" user "F.Silkscreen")
		(7 "B.SilkS" user "B.Silkscreen")
		(1 "F.Mask" user)
		(3 "B.Mask" user)
		(17 "Dwgs.User" user "User.Drawings")
		(19 "Cmts.User" user "User.Comments")
		(21 "Eco1.User" user "User.Eco1")
		(23 "Eco2.User" user "User.Eco2")
		(25 "Edge.Cuts" user)
		(27 "Margin" user)
		(31 "F.CrtYd" user "F.Courtyard")
		(29 "B.CrtYd" user "B.Courtyard")
		(35 "F.Fab" user)
		(33 "B.Fab" user)
	)
	(footprint "antmicro-footprints:C_0402_1005Metric"
		(layer "B.Cu")
		(at 145.631866 79.260116 180)
		(descr "Capacitor SMD 0402")
		(tags "capacitor SMD 0402")
		(property "Reference" "C250"
			(at -17.768134 -9.464883 0)
			(layer "B.SilkS")
			(effects
				(font
					(size 0.7 0.7)
					(thickness 0.15)
				)
				(justify mirror)
			)
		)
		(property "Value" "C_1u_25V_0402"
			(at -1.022927 -2.155213 0)
			(layer "B.Fab")
			(effects
				(font
					(size 0.7 0.7)
					(thickness 0.15)
				)
				(justify left bottom mirror)
			)
		)
		(property "Datasheet" "https://www.murata.com/products/productdetail?partno=GRM155R61E105KE11%23"
			(at 0 0 0)
			(layer "B.Fab")
			(hide yes)
			(effects
				(font
					(size 1.27 1.27)
					(thickness 0.15)
				)
				(justify mirror)
			)
		)
		(property "Description" "SMD Multilayer Ceramic Capacitor, 1 µF, 25 V, 0402 [1005 Metric], ± 10%, X5R, GRM Series"
			(at 0 0 0)
			(layer "B.Fab")
			(hide yes)
			(effects
				(font
					(size 1.27 1.27)
					(thickness 0.15)
				)
				(justify mirror)
			)
		)
		(property "MPN" "GRM155R61E105KE11J"
			(at 0 0 180)
			(unlocked yes)
			(layer "B.Fab")
			(hide yes)
			(effects
				(font
					(size 1 1)
					(thickness 0.15)
				)
				(justify mirror)
			)
		)
		(property "Manufacturer" "Murata"
			(at 0 0 180)
			(unlocked yes)
			(layer "B.Fab")
			(hide yes)
			(effects
				(font
					(size 1 1)
					(thickness 0.15)
				)
				(justify mirror)
			)
		)
		(property "License" "Apache-2.0"
			(at 0 0 180)
			(unlocked yes)
			(layer "B.Fab")
			(hide yes)
			(effects
				(font
					(size 1 1)
					(thickness 0.15)
				)
				(justify mirror)
			)
		)
		(property "Author" "Antmicro"
			(at 0 0 180)
			(unlocked yes)
			(layer "B.Fab")
			(hide yes)
			(effects
				(font
					(size 1 1)
					(thickness 0.15)
				)
				(justify mirror)
			)
		)
		(property "Val" "1u"
			(at 0 0 180)
			(unlocked yes)
			(layer "B.Fab")
			(hide yes)
			(effects
				(font
					(size 1 1)
					(thickness 0.15)
				)
				(justify mirror)
			)
		)
		(property "Voltage" "25V"
			(at 0 0 180)
			(unlocked yes)
			(layer "B.Fab")
			(hide yes)
			(effects
				(font
					(size 1 1)
					(thickness 0.15)
				)
				(justify mirror)
			)
		)
		(property "Dielectric" "X5R"
			(at 0 0 180)
			(unlocked yes)
			(layer "B.Fab")
			(hide yes)
			(effects
				(font
					(size 1 1)
					(thickness 0.15)
				)
				(justify mirror)
			)
		)
		(sheetname "/X710-AT2 power/")
		(sheetfile "x710-at2-power.kicad_sch")
		(attr smd)
		(fp_rect
			(start -0.925 0.47)
			(end 0.925 -0.47)
			(stroke
				(width 0.05)
				(type default)
			)
			(fill no)
			(layer "B.CrtYd")
		)
		(fp_line
			(start 0.504 0.25)
			(end 0.504 -0.248)
			(stroke
				(width 0.15)
				(type solid)
			)
			(layer "B.Fab")
		)
		(fp_line
			(start 0.504 -0.248)
			(end -0.494 -0.248)
			(stroke
				(width 0.15)
				(type solid)
			)
			(layer "B.Fab")
		)
		(fp_line
			(start -0.494 0.25)
			(end 0.504 0.25)
			(stroke
				(width 0.15)
				(type solid)
			)
			(layer "B.Fab")
		)
		(fp_line
			(start -0.494 -0.248)
			(end -0.494 0.25)
			(stroke
				(width 0.15)
				(type solid)
			)
			(layer "B.Fab")
		)
		(fp_text user "${REFERENCE}"
			(at -0.939 -4.599 0)
			(layer "B.Fab")
			(effects
				(font
					(size 0.7 0.7)
					(thickness 0.15)
				)
				(justify left bottom mirror)
			)
		)
		(fp_text user "License: Apache-2.0"
			(at -0.939 -5.799 0)
			(layer "B.Fab")
			(effects
				(font
					(size 0.7 0.7)
					(thickness 0.15)
				)
				(justify left bottom mirror)
			)
		)
		(fp_text user "Author: Antmicro"
			(at -0.939 -3.399 0)
			(layer "B.Fab")
			(effects
				(font
					(size 0.7 0.7)
					(thickness 0.15)
				)
				(justify left bottom mirror)
			)
		)
		(pad "1" smd roundrect
			(at -0.48 0 180)
			(size 0.59 0.64)
			(layers "B.Cu" "B.Mask" "B.Paste")
			(roundrect_rratio 0.25)
			(net 23 "GND")
			(pintype "passive")
		)
		(pad "2" smd roundrect
			(at 0.48 0 180)
			(size 0.59 0.64)
			(layers "B.Cu" "B.Mask" "B.Paste")
			(roundrect_rratio 0.25)
			(net 1 "VCCA")
			(pintype "passive")
		)
	)
	(footprint "antmicro-footprints:R_0402_1005Metric"
		(layer "B.Cu")
		(at 140.6 115.1)
		(descr "Resistor SMD 0402")
		(tags "resistor SMD 0402")
		(property "Reference" "R37"
			(at 19.525001 -7.450001 180)
			(layer "B.SilkS")
			(effects
				(font
					(size 0.7 0.7)
					(thickness 0.15)
				)
				(justify mirror)
			)
		)
		(property "Value" "R_100k_0402"
			(at -1.011843 -1.772047 180)
			(layer "B.Fab")
			(effects
				(font
					(size 0.7 0.7)
					(thickness 0.15)
				)
				(justify left bottom mirror)
			)
		)
		(property "Datasheet" "https://www.bourns.com/docs/product-datasheets/cr.pdf"
			(at 0 0 180)
			(layer "B.Fab")
			(hide yes)
			(effects
				(font
					(size 1.27 1.27)
					(thickness 0.15)
				)
				(justify mirror)
			)
		)
		(property "Description" "SMD Chip Resistor, 100 kohm, ± 1%, 62.5 mW, 0402 [1005 Metric], Thick Film, General Purpose"
			(at 0 0 180)
			(layer "B.Fab")
			(hide yes)
			(effects
				(font
					(size 1.27 1.27)
					(thickness 0.15)
				)
				(justify mirror)
			)
		)
		(property "MPN" "CR0402-FX-1003GLF"
			(at 0 0 0)
			(unlocked yes)
			(layer "B.Fab")
			(hide yes)
			(effects
				(font
					(size 1 1)
					(thickness 0.15)
				)
				(justify mirror)
			)
		)
		(property "Manufacturer" "Bourns"
			(at 0 0 0)
			(unlocked yes)
			(layer "B.Fab")
			(hide yes)
			(effects
				(font
					(size 1 1)
					(thickness 0.15)
				)
				(justify mirror)
			)
		)
		(property "License" "Apache-2.0"
			(at 0 0 0)
			(unlocked yes)
			(layer "B.Fab")
			(hide yes)
			(effects
				(font
					(size 1 1)
					(thickness 0.15)
				)
				(justify mirror)
			)
		)
		(property "Val" "100k"
			(at 0 0 0)
			(unlocked yes)
			(layer "B.Fab")
			(hide yes)
			(effects
				(font
					(size 1 1)
					(thickness 0.15)
				)
				(justify mirror)
			)
		)
		(property "Tolerance" "1%"
			(at 0 0 0)
			(unlocked yes)
			(layer "B.Fab")
			(hide yes)
			(effects
				(font
					(size 1 1)
					(thickness 0.15)
				)
				(justify mirror)
			)
		)
		(property "Author" "Antmicro"
			(at 0 0 0)
			(unlocked yes)
			(layer "B.Fab")
			(hide yes)
			(effects
				(font
					(size 1 1)
					(thickness 0.15)
				)
				(justify mirror)
			)
		)
		(sheetname "/TB Controller/")
		(sheetfile "tb.kicad_sch")
		(attr smd)
		(fp_rect
			(start -0.925 0.47)
			(end 0.925 -0.47)
			(stroke
				(width 0.05)
				(type default)
			)
			(fill no)
			(layer "B.CrtYd")
		)
		(fp_rect
			(start -0.5 0.25)
			(end 0.5 -0.25)
			(stroke
				(width 0.15)
				(type solid)
			)
			(fill no)
			(layer "B.Fab")
		)
		(fp_text user "Author: Antmicro"
			(at -0.95 -4.169 180)
			(layer "B.Fab")
			(effects
				(font
					(size 0.7 0.7)
					(thickness 0.15)
				)
				(justify left bottom mirror)
			)
		)
		(fp_text user "${REFERENCE}"
			(at -0.95 -3.168 180)
			(layer "B.Fab")
			(effects
				(font
					(size 0.7 0.7)
					(thickness 0.15)
				)
				(justify left bottom mirror)
			)
		)
		(fp_text user "License: Apache-2.0"
			(at -0.95 -5.169 180)
			(layer "B.Fab")
			(effects
				(font
					(size 0.7 0.7)
					(thickness 0.15)
				)
				(justify left bottom mirror)
			)
		)
		(pad "1" smd roundrect
			(at -0.48 0)
			(size 0.59 0.64)
			(layers "B.Cu" "B.Mask" "B.Paste")
			(roundrect_rratio 0.25)
			(net 23 "GND")
			(pintype "passive")
		)
		(pad "2" smd roundrect
			(at 0.48 0)
			(size 0.59 0.64)
			(layers "B.Cu" "B.Mask" "B.Paste")
			(roundrect_rratio 0.25)
			(net 220 "Net-(U4C-DPSNK1_HPD)")
			(pintype "passive")
		)
	)
	(footprint "antmicro-footprints:R_0402_1005Metric"
		(layer "B.Cu")
		(at 138.350001 136.599999)
		(descr "Resistor SMD 0402")
		(tags "resistor SMD 0402")
		(property "Reference" "R27"
			(at 19.525001 -8.1 180)
			(layer "B.SilkS")
			(effects
				(font
					(size 0.7 0.7)
					(thickness 0.15)
				)
				(justify mirror)
			)
		)
		(property "Value" "R_100k_0402"
			(at -1.011843 -1.772047 180)
			(layer "B.Fab")
			(effects
				(font
					(size 0.7 0.7)
					(thickness 0.15)
				)
				(justify left bottom mirror)
			)
		)
		(property "Datasheet" "https://www.bourns.com/docs/product-datasheets/cr.pdf"
			(at 0 0 180)
			(layer "B.Fab")
			(hide yes)
			(effects
				(font
					(size 1.27 1.27)
					(thickness 0.15)
				)
				(justify mirror)
			)
		)
		(property "Description" "SMD Chip Resistor, 100 kohm, ± 1%, 62.5 mW, 0402 [1005 Metric], Thick Film, General Purpose"
			(at 0 0 180)
			(layer "B.Fab")
			(hide yes)
			(effects
				(font
					(size 1.27 1.27)
					(thickness 0.15)
				)
				(justify mirror)
			)
		)
		(property "MPN" "CR0402-FX-1003GLF"
			(at 0 0 0)
			(unlocked yes)
			(layer "B.Fab")
			(hide yes)
			(effects
				(font
					(size 1 1)
					(thickness 0.15)
				)
				(justify mirror)
			)
		)
		(property "Manufacturer" "Bourns"
			(at 0 0 0)
			(unlocked yes)
			(layer "B.Fab")
			(hide yes)
			(effects
				(font
					(size 1 1)
					(thickness 0.15)
				)
				(justify mirror)
			)
		)
		(property "License" "Apache-2.0"
			(at 0 0 0)
			(unlocked yes)
			(layer "B.Fab")
			(hide yes)
			(effects
				(font
					(size 1 1)
					(thickness 0.15)
				)
				(justify mirror)
			)
		)
		(property "Val" "100k"
			(at 0 0 0)
			(unlocked yes)
			(layer "B.Fab")
			(hide yes)
			(effects
				(font
					(size 1 1)
					(thickness 0.15)
				)
				(justify mirror)
			)
		)
		(property "Tolerance" "1%"
			(at 0 0 0)
			(unlocked yes)
			(layer "B.Fab")
			(hide yes)
			(effects
				(font
					(size 1 1)
					(thickness 0.15)
				)
				(justify mirror)
			)
		)
		(property "Author" "Antmicro"
			(at 0 0 0)
			(unlocked yes)
			(layer "B.Fab")
			(hide yes)
			(effects
				(font
					(size 1 1)
					(thickness 0.15)
				)
				(justify mirror)
			)
		)
		(sheetname "/PD and TB DC-DC/")
		(sheetfile "PD_and_TB_DC_DC.kicad_sch")
		(attr smd)
		(fp_rect
			(start -0.925 0.47)
			(end 0.925 -0.47)
			(stroke
				(width 0.05)
				(type default)
			)
			(fill no)
			(layer "B.CrtYd")
		)
		(fp_rect
			(start -0.5 0.25)
			(end 0.5 -0.25)
			(stroke
				(width 0.15)
				(type solid)
			)
			(fill no)
			(layer "B.Fab")
		)
		(fp_text user "Author: Antmicro"
			(at -0.95 -4.169 180)
			(layer "B.Fab")
			(effects
				(font
					(size 0.7 0.7)
					(thickness 0.15)
				)
				(justify left bottom mirror)
			)
		)
		(fp_text user "${REFERENCE}"
			(at -0.95 -3.168 180)
			(layer "B.Fab")
			(effects
				(font
					(size 0.7 0.7)
					(thickness 0.15)
				)
				(justify left bottom mirror)
			)
		)
		(fp_text user "License: Apache-2.0"
			(at -0.95 -5.169 180)
			(layer "B.Fab")
			(effects
				(font
					(size 0.7 0.7)
					(thickness 0.15)
				)
				(justify left bottom mirror)
			)
		)
		(pad "1" smd roundrect
			(at -0.48 0)
			(size 0.59 0.64)
			(layers "B.Cu" "B.Mask" "B.Paste")
			(roundrect_rratio 0.25)
			(net 210 "Net-(U3-HRESET)")
			(pintype "passive")
		)
		(pad "2" smd roundrect
			(at 0.48 0)
			(size 0.59 0.64)
			(layers "B.Cu" "B.Mask" "B.Paste")
			(roundrect_rratio 0.25)
			(net 23 "GND")
			(pintype "passive")
		)
	)
	(footprint "antmicro-footprints:C_0402_1005Metric"
		(layer "B.Cu")
		(at 147.481866 79.260117 180)
		(descr "Capacitor SMD 0402")
		(tags "capacitor SMD 0402")
		(property "Reference" "C223"
			(at -18.618135 -9.464883 0)
			(layer "B.SilkS")
			(effects
				(font
					(size 0.7 0.7)
					(thickness 0.15)
				)
				(justify mirror)
			)
		)
		(property "Value" "C_1u_25V_0402"
			(at -1.022927 -2.155213 0)
			(layer "B.Fab")
			(effects
				(font
					(size 0.7 0.7)
					(thickness 0.15)
				)
				(justify left bottom mirror)
			)
		)
		(property "Datasheet" "https://www.murata.com/products/productdetail?partno=GRM155R61E105KE11%23"
			(at 0 0 0)
			(layer "B.Fab")
			(hide yes)
			(effects
				(font
					(size 1.27 1.27)
					(thickness 0.15)
				)
				(justify mirror)
			)
		)
		(property "Description" "SMD Multilayer Ceramic Capacitor, 1 µF, 25 V, 0402 [1005 Metric], ± 10%, X5R, GRM Series"
			(at 0 0 0)
			(layer "B.Fab")
			(hide yes)
			(effects
				(font
					(size 1.27 1.27)
					(thickness 0.15)
				)
				(justify mirror)
			)
		)
		(property "MPN" "GRM155R61E105KE11J"
			(at 0 0 180)
			(unlocked yes)
			(layer "B.Fab")
			(hide yes)
			(effects
				(font
					(size 1 1)
					(thickness 0.15)
				)
				(justify mirror)
			)
		)
		(property "Manufacturer" "Murata"
			(at 0 0 180)
			(unlocked yes)
			(layer "B.Fab")
			(hide yes)
			(effects
				(font
					(size 1 1)
					(thickness 0.15)
				)
				(justify mirror)
			)
		)
		(property "License" "Apache-2.0"
			(at 0 0 180)
			(unlocked yes)
			(layer "B.Fab")
			(hide yes)
			(effects
				(font
					(size 1 1)
					(thickness 0.15)
				)
				(justify mirror)
			)
		)
		(property "Author" "Antmicro"
			(at 0 0 180)
			(unlocked yes)
			(layer "B.Fab")
			(hide yes)
			(effects
				(font
					(size 1 1)
					(thickness 0.15)
				)
				(justify mirror)
			)
		)
		(property "Val" "1u"
			(at 0 0 180)
			(unlocked yes)
			(layer "B.Fab")
			(hide yes)
			(effects
				(font
					(size 1 1)
					(thickness 0.15)
				)
				(justify mirror)
			)
		)
		(property "Voltage" "25V"
			(at 0 0 180)
			(unlocked yes)
			(layer "B.Fab")
			(hide yes)
			(effects
				(font
					(size 1 1)
					(thickness 0.15)
				)
				(justify mirror)
			)
		)
		(property "Dielectric" "X5R"
			(at 0 0 180)
			(unlocked yes)
			(layer "B.Fab")
			(hide yes)
			(effects
				(font
					(size 1 1)
					(thickness 0.15)
				)
				(justify mirror)
			)
		)
		(sheetname "/X710-AT2 power/")
		(sheetfile "x710-at2-power.kicad_sch")
		(attr smd)
		(fp_rect
			(start -0.925 0.47)
			(end 0.925 -0.47)
			(stroke
				(width 0.05)
				(type default)
			)
			(fill no)
			(layer "B.CrtYd")
		)
		(fp_line
			(start 0.504 0.25)
			(end 0.504 -0.248)
			(stroke
				(width 0.15)
				(type solid)
			)
			(layer "B.Fab")
		)
		(fp_line
			(start 0.504 -0.248)
			(end -0.494 -0.248)
			(stroke
				(width 0.15)
				(type solid)
			)
			(layer "B.Fab")
		)
		(fp_line
			(start -0.494 0.25)
			(end 0.504 0.25)
			(stroke
				(width 0.15)
				(type solid)
			)
			(layer "B.Fab")
		)
		(fp_line
			(start -0.494 -0.248)
			(end -0.494 0.25)
			(stroke
				(width 0.15)
				(type solid)
			)
			(layer "B.Fab")
		)
		(fp_text user "Author: Antmicro"
			(at -0.939 -3.399 0)
			(layer "B.Fab")
			(effects
				(font
					(size 0.7 0.7)
					(thickness 0.15)
				)
				(justify left bottom mirror)
			)
		)
		(fp_text user "License: Apache-2.0"
			(at -0.939 -5.799 0)
			(layer "B.Fab")
			(effects
				(font
					(size 0.7 0.7)
					(thickness 0.15)
				)
				(justify left bottom mirror)
			)
		)
		(fp_text user "${REFERENCE}"
			(at -0.939 -4.599 0)
			(layer "B.Fab")
			(effects
				(font
					(size 0.7 0.7)
					(thickness 0.15)
				)
				(justify left bottom mirror)
			)
		)
		(pad "1" smd roundrect
			(at -0.48 0 180)
			(size 0.59 0.64)
			(layers "B.Cu" "B.Mask" "B.Paste")
			(roundrect_rratio 0.25)
			(net 23 "GND")
			(pintype "passive")
		)
		(pad "2" smd roundrect
			(at 0.48 0 180)
			(size 0.59 0.64)
			(layers "B.Cu" "B.Mask" "B.Paste")
			(roundrect_rratio 0.25)
			(net 9 "VCCD")
			(pintype "passive")
		)
	)
	(footprint "antmicro-footprints:R_0402_1005Metric"
		(layer "B.Cu")
		(at 172.58 146.66 90)
		(descr "Resistor SMD 0402")
		(tags "resistor SMD 0402")
		(property "Reference" "R215"
			(at -1.09 0.42 270)
			(layer "B.SilkS")
			(effects
				(font
					(size 0.7 0.7)
					(thickness 0.15)
				)
				(justify left bottom mirror)
			)
		)
		(property "Value" "R_220R_0402"
			(at -1.011843 -1.772047 270)
			(layer "B.Fab")
			(effects
				(font
					(size 0.7 0.7)
					(thickness 0.15)
				)
				(justify left bottom mirror)
			)
		)
		(property "Datasheet" "https://www.bourns.com/docs/product-datasheets/cr.pdf"
			(at 0 0 270)
			(layer "B.Fab")
			(hide yes)
			(effects
				(font
					(size 1.27 1.27)
					(thickness 0.15)
				)
				(justify mirror)
			)
		)
		(property "Description" "SMD Chip Resistor, 220 ohm, ± 1%, 62.5 mW, 0402 [1005 Metric], Thick Film, General Purpose"
			(at 0 0 270)
			(layer "B.Fab")
			(hide yes)
			(effects
				(font
					(size 1.27 1.27)
					(thickness 0.15)
				)
				(justify mirror)
			)
		)
		(property "MPN" "CR0402-FX-2200GLF"
			(at 0 0 90)
			(unlocked yes)
			(layer "B.Fab")
			(hide yes)
			(effects
				(font
					(size 1 1)
					(thickness 0.15)
				)
				(justify mirror)
			)
		)
		(property "Manufacturer" "Bourns"
			(at 0 0 90)
			(unlocked yes)
			(layer "B.Fab")
			(hide yes)
			(effects
				(font
					(size 1 1)
					(thickness 0.15)
				)
				(justify mirror)
			)
		)
		(property "License" "Apache-2.0"
			(at 0 0 90)
			(unlocked yes)
			(layer "B.Fab")
			(hide yes)
			(effects
				(font
					(size 1 1)
					(thickness 0.15)
				)
				(justify mirror)
			)
		)
		(property "Author" "Antmicro"
			(at 0 0 90)
			(unlocked yes)
			(layer "B.Fab")
			(hide yes)
			(effects
				(font
					(size 1 1)
					(thickness 0.15)
				)
				(justify mirror)
			)
		)
		(property "Val" "220R"
			(at 0 0 90)
			(unlocked yes)
			(layer "B.Fab")
			(hide yes)
			(effects
				(font
					(size 1 1)
					(thickness 0.15)
				)
				(justify mirror)
			)
		)
		(property "Tolerance" "1%"
			(at 0 0 90)
			(unlocked yes)
			(layer "B.Fab")
			(hide yes)
			(effects
				(font
					(size 1 1)
					(thickness 0.15)
				)
				(justify mirror)
			)
		)
		(sheetname "/2xRJ45/")
		(sheetfile "2xrj45.kicad_sch")
		(attr smd)
		(fp_rect
			(start -0.925 0.47)
			(end 0.925 -0.47)
			(stroke
				(width 0.05)
				(type default)
			)
			(fill no)
			(layer "B.CrtYd")
		)
		(fp_rect
			(start -0.5 0.25)
			(end 0.5 -0.25)
			(stroke
				(width 0.15)
				(type solid)
			)
			(fill no)
			(layer "B.Fab")
		)
		(fp_text user "${REFERENCE}"
			(at -0.95 -3.168 270)
			(layer "B.Fab")
			(effects
				(font
					(size 0.7 0.7)
					(thickness 0.15)
				)
				(justify left bottom mirror)
			)
		)
		(fp_text user "Author: Antmicro"
			(at -0.95 -4.169 270)
			(layer "B.Fab")
			(effects
				(font
					(size 0.7 0.7)
					(thickness 0.15)
				)
				(justify left bottom mirror)
			)
		)
		(fp_text user "License: Apache-2.0"
			(at -0.95 -5.169 270)
			(layer "B.Fab")
			(effects
				(font
					(size 0.7 0.7)
					(thickness 0.15)
				)
				(justify left bottom mirror)
			)
		)
		(pad "1" smd roundrect
			(at -0.48 0 90)
			(size 0.59 0.64)
			(layers "B.Cu" "B.Mask" "B.Paste")
			(roundrect_rratio 0.25)
			(net 411 "Net-(J4-LED_GRN-)")
			(pintype "passive")
		)
		(pad "2" smd roundrect
			(at 0.48 0 90)
			(size 0.59 0.64)
			(layers "B.Cu" "B.Mask" "B.Paste")
			(roundrect_rratio 0.25)
			(net 67 "/2xRJ45/~{P1_LED_ACT}")
			(pintype "passive")
		)
	)
)
